# T6G (Grand Teton) — schematic netlist excerpt (pin names and nets, part order shuffled) for the footprints in the layout excerpt that follows; sources: Cadence DE-HDL packaged netlist, KiCad conversion of 04192023_DAF0TMB3IC0_F0TG_MB_C_brd_V02_OCP.brd

C2518  Q_CAP  22UF 4V 20% X6S  pkg C0402  page 71 : A = PVDD18_S5_P0 ; B = GND
R261  Q_RES  0 5% CHIP  pkg 0402LF  page 82 : A = CPU1_SP5R2 ; B = FM_CPU1_SP5R2
C599  Q_CAP  1UF 4V 20% X6S  pkg 0201  page 290 : A = P1V8_CPU0_RT1_1A ; B = GND

(kicad_pcb
	(version 20260206)
	(generator "pcbnew")
	(generator_version "10.0")
	(general
		(thickness 1.6)
		(legacy_teardrops no)
	)
	(paper "A4")
	(title_block
		(title "04192023_DAF0TMB3IC0_F0TG_MB_C_brd_V02_OCP.brd")
		(comment 1 "Grand Teton / footprints 7446-7448 of 8354")
	)
	(layers
		(0 "F.Cu" signal "TOP")
		(4 "In1.Cu" signal "GND")
		(6 "In2.Cu" signal "IN1")
		(8 "In3.Cu" signal "GND1")
		(10 "In4.Cu" signal "IN2")
		(12 "In5.Cu" signal "GND2")
		(14 "In6.Cu" signal "IN3")
		(16 "In7.Cu" signal "GND3")
		(18 "In8.Cu" signal "VCC")
		(20 "In9.Cu" signal "VCC1")
		(22 "In10.Cu" signal "GND4")
		(24 "In11.Cu" signal "IN4")
		(26 "In12.Cu" signal "GND5")
		(28 "In13.Cu" signal "IN5")
		(30 "In14.Cu" signal "GND6")
		(32 "In15.Cu" signal "IN6")
		(34 "In16.Cu" signal "GND7")
		(2 "B.Cu" signal "BOTTOM")
		(9 "F.Adhes" user "F.Adhesive")
		(11 "B.Adhes" user "B.Adhesive")
		(13 "F.Paste" user "Package Geometry/Pastemask Top")
		(15 "B.Paste" user "Package Geometry/Pastemask Bottom")
		(5 "F.SilkS" user "Ref Des/Silkscreen Top")
		(7 "B.SilkS" user "Ref Des/Silkscreen Bottom")
		(1 "F.Mask" user "Board Geometry/Soldermask Top")
		(3 "B.Mask" user "Board Geometry/Soldermask Bottom")
		(17 "Dwgs.User" user "User.Drawings")
		(19 "Cmts.User" user "User.Comments")
		(21 "Eco1.User" user "User.Eco1")
		(23 "Eco2.User" user "User.Eco2")
		(25 "Edge.Cuts" user "Board Geometry/Outline")
		(27 "Margin" user)
		(31 "F.CrtYd" user "Package Geometry/Place Bound Top")
		(29 "B.CrtYd" user "Package Geometry/Place Bound Bottom")
		(35 "F.Fab" user "Ref Des/Assembly Top")
		(33 "B.Fab" user "Ref Des/Assembly Bottom")
	)
	(footprint ""
		(layer "B.Cu")
		(at 188.838078 -97.085912 -90)
		(property "Reference" "R261"
			(at 0 0 90)
			(layer "B.SilkS")
			(hide yes)
			(effects
				(font
					(size 1.27 1.27)
				)
				(justify mirror)
			)
		)
		(property "Value" ""
			(at 0 0 90)
			(layer "B.Fab")
			(effects
				(font
					(size 1.27 1.27)
				)
				(justify mirror)
			)
		)
		(duplicate_pad_numbers_are_jumpers no)
		(fp_line
			(start -0.7874 0.4064)
			(end 0.7874 0.4064)
			(stroke
				(width 0.1524)
				(type default)
			)
			(layer "B.SilkS")
		)
		(fp_line
			(start 0.7874 0.4064)
			(end 0.7874 -0.4064)
			(stroke
				(width 0.1524)
				(type default)
			)
			(layer "B.SilkS")
		)
		(fp_line
			(start -0.7874 -0.4064)
			(end -0.7874 0.4064)
			(stroke
				(width 0.1524)
				(type default)
			)
			(layer "B.SilkS")
		)
		(fp_line
			(start 0.7874 -0.4064)
			(end -0.7874 -0.4064)
			(stroke
				(width 0.1524)
				(type default)
			)
			(layer "B.SilkS")
		)
		(fp_line
			(start -0.67945 0.3048)
			(end -0.120396 0.3048)
			(stroke
				(width 0.1)
				(type default)
			)
			(layer "B.Fab")
		)
		(fp_line
			(start -0.120396 0.3048)
			(end -0.120396 0.2794)
			(stroke
				(width 0.1)
				(type default)
			)
			(layer "B.Fab")
		)
		(fp_line
			(start 0.12065 0.3048)
			(end 0.67945 0.3048)
			(stroke
				(width 0.1)
				(type default)
			)
			(layer "B.Fab")
		)
		(fp_line
			(start 0.67945 0.3048)
			(end 0.67945 -0.305054)
			(stroke
				(width 0.1)
				(type default)
			)
			(layer "B.Fab")
		)
		(fp_line
			(start -0.120396 0.2794)
			(end 0.12065 0.2794)
			(stroke
				(width 0.1)
				(type default)
			)
			(layer "B.Fab")
		)
		(fp_line
			(start 0.12065 0.2794)
			(end 0.12065 0.3048)
			(stroke
				(width 0.1)
				(type default)
			)
			(layer "B.Fab")
		)
		(fp_line
			(start -0.12065 -0.2794)
			(end -0.12065 -0.3048)
			(stroke
				(width 0.1)
				(type default)
			)
			(layer "B.Fab")
		)
		(fp_line
			(start 0.12065 -0.2794)
			(end -0.12065 -0.2794)
			(stroke
				(width 0.1)
				(type default)
			)
			(layer "B.Fab")
		)
		(fp_line
			(start -0.67945 -0.3048)
			(end -0.67945 0.3048)
			(stroke
				(width 0.1)
				(type default)
			)
			(layer "B.Fab")
		)
		(fp_line
			(start -0.12065 -0.3048)
			(end -0.67945 -0.3048)
			(stroke
				(width 0.1)
				(type default)
			)
			(layer "B.Fab")
		)
		(fp_line
			(start 0.12065 -0.305054)
			(end 0.12065 -0.2794)
			(stroke
				(width 0.1)
				(type default)
			)
			(layer "B.Fab")
		)
		(fp_line
			(start 0.67945 -0.305054)
			(end 0.12065 -0.305054)
			(stroke
				(width 0.1)
				(type default)
			)
			(layer "B.Fab")
		)
		(pad "1" smd circle
			(at 0.40005 0 90)
			(size 0 0)
			(layers "B.Cu" "B.Mask" "B.Paste")
			(net "CPU1_SP5R2")
		)
		(pad "2" smd circle
			(at -0.40005 0 90)
			(size 0 0)
			(layers "B.Cu" "B.Mask" "B.Paste")
			(net "FM_CPU1_SP5R2")
		)
	)
	(footprint ""
		(layer "B.Cu")
		(at 348.786958 -252.54331 180)
		(property "Reference" "C2518"
			(at 0 0 0)
			(layer "B.SilkS")
			(hide yes)
			(effects
				(font
					(size 1.27 1.27)
				)
				(justify mirror)
			)
		)
		(property "Value" ""
			(at 0 0 0)
			(layer "B.Fab")
			(effects
				(font
					(size 1.27 1.27)
				)
				(justify mirror)
			)
		)
		(duplicate_pad_numbers_are_jumpers no)
		(fp_line
			(start 0.7874 0.4064)
			(end 0.7874 -0.4064)
			(stroke
				(width 0.1524)
				(type default)
			)
			(layer "B.SilkS")
		)
		(fp_line
			(start 0.7874 -0.4064)
			(end -0.7874 -0.4064)
			(stroke
				(width 0.1524)
				(type default)
			)
			(layer "B.SilkS")
		)
		(fp_line
			(start -0.7874 0.4064)
			(end 0.7874 0.4064)
			(stroke
				(width 0.1524)
				(type default)
			)
			(layer "B.SilkS")
		)
		(fp_line
			(start -0.7874 -0.4064)
			(end -0.7874 0.4064)
			(stroke
				(width 0.1524)
				(type default)
			)
			(layer "B.SilkS")
		)
		(fp_line
			(start 0.67945 0.3048)
			(end 0.67945 -0.305054)
			(stroke
				(width 0.1)
				(type default)
			)
			(layer "B.Fab")
		)
		(fp_line
			(start 0.67945 -0.305054)
			(end 0.12065 -0.305054)
			(stroke
				(width 0.1)
				(type default)
			)
			(layer "B.Fab")
		)
		(fp_line
			(start 0.12065 0.3048)
			(end 0.67945 0.3048)
			(stroke
				(width 0.1)
				(type default)
			)
			(layer "B.Fab")
		)
		(fp_line
			(start 0.12065 0.2794)
			(end 0.12065 0.3048)
			(stroke
				(width 0.1)
				(type default)
			)
			(layer "B.Fab")
		)
		(fp_line
			(start 0.12065 -0.2794)
			(end -0.12065 -0.2794)
			(stroke
				(width 0.1)
				(type default)
			)
			(layer "B.Fab")
		)
		(fp_line
			(start 0.12065 -0.305054)
			(end 0.12065 -0.2794)
			(stroke
				(width 0.1)
				(type default)
			)
			(layer "B.Fab")
		)
		(fp_line
			(start -0.120396 0.3048)
			(end -0.120396 0.2794)
			(stroke
				(width 0.1)
				(type default)
			)
			(layer "B.Fab")
		)
		(fp_line
			(start -0.120396 0.2794)
			(end 0.12065 0.2794)
			(stroke
				(width 0.1)
				(type default)
			)
			(layer "B.Fab")
		)
		(fp_line
			(start -0.12065 -0.2794)
			(end -0.12065 -0.3048)
			(stroke
				(width 0.1)
				(type default)
			)
			(layer "B.Fab")
		)
		(fp_line
			(start -0.12065 -0.3048)
			(end -0.67945 -0.3048)
			(stroke
				(width 0.1)
				(type default)
			)
			(layer "B.Fab")
		)
		(fp_line
			(start -0.67945 0.3048)
			(end -0.120396 0.3048)
			(stroke
				(width 0.1)
				(type default)
			)
			(layer "B.Fab")
		)
		(fp_line
			(start -0.67945 -0.3048)
			(end -0.67945 0.3048)
			(stroke
				(width 0.1)
				(type default)
			)
			(layer "B.Fab")
		)
		(pad "1" smd circle
			(at 0.40005 0)
			(size 0 0)
			(layers "B.Cu" "B.Mask" "B.Paste")
			(net "PVDD18_S5_P0")
		)
		(pad "2" smd circle
			(at -0.40005 0)
			(size 0 0)
			(layers "B.Cu" "B.Mask" "B.Paste")
			(net "GND")
		)
	)
	(footprint ""
		(layer "B.Cu")
		(at 344.446098 -396.393162 -90)
		(property "Reference" "C599"
			(at 0 0 90)
			(layer "B.SilkS")
			(hide yes)
			(effects
				(font
					(size 1.27 1.27)
				)
				(justify mirror)
			)
		)
		(property "Value" ""
			(at 0 0 90)
			(layer "B.Fab")
			(effects
				(font
					(size 1.27 1.27)
				)
				(justify mirror)
			)
		)
		(duplicate_pad_numbers_are_jumpers no)
		(fp_line
			(start -0.299974 0.150114)
			(end 0.299974 0.150114)
			(stroke
				(width 0.1)
				(type default)
			)
			(layer "B.Fab")
		)
		(fp_line
			(start 0.299974 0.150114)
			(end 0.299974 -0.150114)
			(stroke
				(width 0.1)
				(type default)
			)
			(layer "B.Fab")
		)
		(fp_line
			(start -0.299974 -0.150114)
			(end -0.299974 0.150114)
			(stroke
				(width 0.1)
				(type default)
			)
			(layer "B.Fab")
		)
		(fp_line
			(start 0.299974 -0.150114)
			(end -0.299974 -0.150114)
			(stroke
				(width 0.1)
				(type default)
			)
			(layer "B.Fab")
		)
		(pad "1" smd rect
			(at 0.2667 0 90)
			(size 0.3048 0.381)
			(layers "B.Cu" "B.Mask" "B.Paste")
			(net "P1V8_CPU0_RT1_1A")
		)
		(pad "2" smd rect
			(at -0.2667 0 90)
			(size 0.3048 0.381)
			(layers "B.Cu" "B.Mask" "B.Paste")
			(net "GND")
		)
	)
)
